# T6G (Grand Teton) — schematic netlist excerpt (pin names and nets, part order shuffled) for the footprints in the layout excerpt that follows; sources: Cadence DE-HDL packaged netlist, KiCad conversion of 04192023_DAF0TMB3IC0_F0TG_MB_C_brd_V02_OCP.brd

R2812  Q_RES  33.2 1% CHIP  pkg 0402LF  page 240 : A = SMB_FAN_3V3AUX_BUF_SDA ; B = SMB_FAN_3V3AUX_BUF_R_SDA
C163  Q_CAP  10UF 25V 10% X6S  pkg C0805  page 94 : A = P12V_MEM_CPU0 ; B = GND
C2586  Q_CAP  22UF 4V 20% X6S  pkg C0402  page 70 : A = PVDDCR_SOC_P0 ; B = GND

(kicad_pcb
	(version 20260206)
	(generator "pcbnew")
	(generator_version "10.0")
	(general
		(thickness 1.6)
		(legacy_teardrops no)
	)
	(paper "A4")
	(title_block
		(title "04192023_DAF0TMB3IC0_F0TG_MB_C_brd_V02_OCP.brd")
		(comment 1 "Grand Teton / footprints 8079-8081 of 8354")
	)
	(layers
		(0 "F.Cu" signal "TOP")
		(4 "In1.Cu" signal "GND")
		(6 "In2.Cu" signal "IN1")
		(8 "In3.Cu" signal "GND1")
		(10 "In4.Cu" signal "IN2")
		(12 "In5.Cu" signal "GND2")
		(14 "In6.Cu" signal "IN3")
		(16 "In7.Cu" signal "GND3")
		(18 "In8.Cu" signal "VCC")
		(20 "In9.Cu" signal "VCC1")
		(22 "In10.Cu" signal "GND4")
		(24 "In11.Cu" signal "IN4")
		(26 "In12.Cu" signal "GND5")
		(28 "In13.Cu" signal "IN5")
		(30 "In14.Cu" signal "GND6")
		(32 "In15.Cu" signal "IN6")
		(34 "In16.Cu" signal "GND7")
		(2 "B.Cu" signal "BOTTOM")
		(9 "F.Adhes" user "F.Adhesive")
		(11 "B.Adhes" user "B.Adhesive")
		(13 "F.Paste" user "Package Geometry/Pastemask Top")
		(15 "B.Paste" user "Package Geometry/Pastemask Bottom")
		(5 "F.SilkS" user "Ref Des/Silkscreen Top")
		(7 "B.SilkS" user "Ref Des/Silkscreen Bottom")
		(1 "F.Mask" user "Board Geometry/Soldermask Top")
		(3 "B.Mask" user "Board Geometry/Soldermask Bottom")
		(17 "Dwgs.User" user "User.Drawings")
		(19 "Cmts.User" user "User.Comments")
		(21 "Eco1.User" user "User.Eco1")
		(23 "Eco2.User" user "User.Eco2")
		(25 "Edge.Cuts" user "Board Geometry/Outline")
		(27 "Margin" user)
		(31 "F.CrtYd" user "Package Geometry/Place Bound Top")
		(29 "B.CrtYd" user "Package Geometry/Place Bound Bottom")
		(35 "F.Fab" user "Ref Des/Assembly Top")
		(33 "B.Fab" user "Ref Des/Assembly Bottom")
	)
	(footprint ""
		(layer "B.Cu")
		(at 369.646454 -254.19431)
		(property "Reference" "C2586"
			(at 0 0 0)
			(layer "B.SilkS")
			(hide yes)
			(effects
				(font
					(size 1.27 1.27)
				)
				(justify mirror)
			)
		)
		(property "Value" ""
			(at 0 0 0)
			(layer "B.Fab")
			(effects
				(font
					(size 1.27 1.27)
				)
				(justify mirror)
			)
		)
		(duplicate_pad_numbers_are_jumpers no)
		(fp_line
			(start -0.7874 -0.4064)
			(end -0.7874 0.4064)
			(stroke
				(width 0.1524)
				(type default)
			)
			(layer "B.SilkS")
		)
		(fp_line
			(start -0.7874 0.4064)
			(end 0.7874 0.4064)
			(stroke
				(width 0.1524)
				(type default)
			)
			(layer "B.SilkS")
		)
		(fp_line
			(start 0.7874 -0.4064)
			(end -0.7874 -0.4064)
			(stroke
				(width 0.1524)
				(type default)
			)
			(layer "B.SilkS")
		)
		(fp_line
			(start 0.7874 0.4064)
			(end 0.7874 -0.4064)
			(stroke
				(width 0.1524)
				(type default)
			)
			(layer "B.SilkS")
		)
		(fp_line
			(start -0.67945 -0.3048)
			(end -0.67945 0.3048)
			(stroke
				(width 0.1)
				(type default)
			)
			(layer "B.Fab")
		)
		(fp_line
			(start -0.67945 0.3048)
			(end -0.120396 0.3048)
			(stroke
				(width 0.1)
				(type default)
			)
			(layer "B.Fab")
		)
		(fp_line
			(start -0.12065 -0.3048)
			(end -0.67945 -0.3048)
			(stroke
				(width 0.1)
				(type default)
			)
			(layer "B.Fab")
		)
		(fp_line
			(start -0.12065 -0.2794)
			(end -0.12065 -0.3048)
			(stroke
				(width 0.1)
				(type default)
			)
			(layer "B.Fab")
		)
		(fp_line
			(start -0.120396 0.2794)
			(end 0.12065 0.2794)
			(stroke
				(width 0.1)
				(type default)
			)
			(layer "B.Fab")
		)
		(fp_line
			(start -0.120396 0.3048)
			(end -0.120396 0.2794)
			(stroke
				(width 0.1)
				(type default)
			)
			(layer "B.Fab")
		)
		(fp_line
			(start 0.12065 -0.305054)
			(end 0.12065 -0.2794)
			(stroke
				(width 0.1)
				(type default)
			)
			(layer "B.Fab")
		)
		(fp_line
			(start 0.12065 -0.2794)
			(end -0.12065 -0.2794)
			(stroke
				(width 0.1)
				(type default)
			)
			(layer "B.Fab")
		)
		(fp_line
			(start 0.12065 0.2794)
			(end 0.12065 0.3048)
			(stroke
				(width 0.1)
				(type default)
			)
			(layer "B.Fab")
		)
		(fp_line
			(start 0.12065 0.3048)
			(end 0.67945 0.3048)
			(stroke
				(width 0.1)
				(type default)
			)
			(layer "B.Fab")
		)
		(fp_line
			(start 0.67945 -0.305054)
			(end 0.12065 -0.305054)
			(stroke
				(width 0.1)
				(type default)
			)
			(layer "B.Fab")
		)
		(fp_line
			(start 0.67945 0.3048)
			(end 0.67945 -0.305054)
			(stroke
				(width 0.1)
				(type default)
			)
			(layer "B.Fab")
		)
		(pad "1" smd circle
			(at 0.40005 0 180)
			(size 0 0)
			(layers "B.Cu" "B.Mask" "B.Paste")
			(net "PVDDCR_SOC_P0")
		)
		(pad "2" smd circle
			(at -0.40005 0 180)
			(size 0 0)
			(layers "B.Cu" "B.Mask" "B.Paste")
			(net "GND")
		)
	)
	(footprint ""
		(layer "B.Cu")
		(at 431.55616 -192.660016)
		(property "Reference" "C163"
			(at 0 0 0)
			(layer "B.SilkS")
			(hide yes)
			(effects
				(font
					(size 1.27 1.27)
				)
				(justify mirror)
			)
		)
		(property "Value" ""
			(at 0 0 0)
			(layer "B.Fab")
			(effects
				(font
					(size 1.27 1.27)
				)
				(justify mirror)
			)
		)
		(duplicate_pad_numbers_are_jumpers no)
		(fp_line
			(start -1.524 -0.762)
			(end -1.524 0.762)
			(stroke
				(width 0.1524)
				(type default)
			)
			(layer "B.SilkS")
		)
		(fp_line
			(start -1.524 0.762)
			(end 1.524 0.762)
			(stroke
				(width 0.1524)
				(type default)
			)
			(layer "B.SilkS")
		)
		(fp_line
			(start 1.524 -0.762)
			(end -1.524 -0.762)
			(stroke
				(width 0.1524)
				(type default)
			)
			(layer "B.SilkS")
		)
		(fp_line
			(start 1.524 0.762)
			(end 1.524 -0.762)
			(stroke
				(width 0.1524)
				(type default)
			)
			(layer "B.SilkS")
		)
		(fp_line
			(start -1.1049 -0.724916)
			(end 1.1049 -0.724916)
			(stroke
				(width 0.1)
				(type default)
			)
			(layer "B.Fab")
		)
		(fp_line
			(start -1.1049 0.724916)
			(end -1.1049 -0.724916)
			(stroke
				(width 0.1)
				(type default)
			)
			(layer "B.Fab")
		)
		(fp_line
			(start 1.1049 -0.724916)
			(end 1.1049 0.724916)
			(stroke
				(width 0.1)
				(type default)
			)
			(layer "B.Fab")
		)
		(fp_line
			(start 1.1049 0.724916)
			(end -1.1049 0.724916)
			(stroke
				(width 0.1)
				(type default)
			)
			(layer "B.Fab")
		)
		(pad "1" smd rect
			(at 0.889 0)
			(size 1.016 1.27)
			(layers "B.Cu" "B.Mask" "B.Paste")
			(net "P12V_MEM_CPU0")
		)
		(pad "2" smd rect
			(at -0.889 0)
			(size 1.016 1.27)
			(layers "B.Cu" "B.Mask" "B.Paste")
			(net "GND")
		)
	)
	(footprint ""
		(layer "B.Cu")
		(at 172.312838 -418.190426)
		(property "Reference" "R2812"
			(at 0 0 0)
			(layer "B.SilkS")
			(hide yes)
			(effects
				(font
					(size 1.27 1.27)
				)
				(justify mirror)
			)
		)
		(property "Value" ""
			(at 0 0 0)
			(layer "B.Fab")
			(effects
				(font
					(size 1.27 1.27)
				)
				(justify mirror)
			)
		)
		(duplicate_pad_numbers_are_jumpers no)
		(fp_line
			(start -0.7874 -0.4064)
			(end -0.7874 0.4064)
			(stroke
				(width 0.1524)
				(type default)
			)
			(layer "B.SilkS")
		)
		(fp_line
			(start -0.7874 0.4064)
			(end 0.7874 0.4064)
			(stroke
				(width 0.1524)
				(type default)
			)
			(layer "B.SilkS")
		)
		(fp_line
			(start 0.7874 -0.4064)
			(end -0.7874 -0.4064)
			(stroke
				(width 0.1524)
				(type default)
			)
			(layer "B.SilkS")
		)
		(fp_line
			(start 0.7874 0.4064)
			(end 0.7874 -0.4064)
			(stroke
				(width 0.1524)
				(type default)
			)
			(layer "B.SilkS")
		)
		(fp_line
			(start -0.67945 -0.3048)
			(end -0.67945 0.3048)
			(stroke
				(width 0.1)
				(type default)
			)
			(layer "B.Fab")
		)
		(fp_line
			(start -0.67945 0.3048)
			(end -0.120396 0.3048)
			(stroke
				(width 0.1)
				(type default)
			)
			(layer "B.Fab")
		)
		(fp_line
			(start -0.12065 -0.3048)
			(end -0.67945 -0.3048)
			(stroke
				(width 0.1)
				(type default)
			)
			(layer "B.Fab")
		)
		(fp_line
			(start -0.12065 -0.2794)
			(end -0.12065 -0.3048)
			(stroke
				(width 0.1)
				(type default)
			)
			(layer "B.Fab")
		)
		(fp_line
			(start -0.120396 0.2794)
			(end 0.12065 0.2794)
			(stroke
				(width 0.1)
				(type default)
			)
			(layer "B.Fab")
		)
		(fp_line
			(start -0.120396 0.3048)
			(end -0.120396 0.2794)
			(stroke
				(width 0.1)
				(type default)
			)
			(layer "B.Fab")
		)
		(fp_line
			(start 0.12065 -0.305054)
			(end 0.12065 -0.2794)
			(stroke
				(width 0.1)
				(type default)
			)
			(layer "B.Fab")
		)
		(fp_line
			(start 0.12065 -0.2794)
			(end -0.12065 -0.2794)
			(stroke
				(width 0.1)
				(type default)
			)
			(layer "B.Fab")
		)
		(fp_line
			(start 0.12065 0.2794)
			(end 0.12065 0.3048)
			(stroke
				(width 0.1)
				(type default)
			)
			(layer "B.Fab")
		)
		(fp_line
			(start 0.12065 0.3048)
			(end 0.67945 0.3048)
			(stroke
				(width 0.1)
				(type default)
			)
			(layer "B.Fab")
		)
		(fp_line
			(start 0.67945 -0.305054)
			(end 0.12065 -0.305054)
			(stroke
				(width 0.1)
				(type default)
			)
			(layer "B.Fab")
		)
		(fp_line
			(start 0.67945 0.3048)
			(end 0.67945 -0.305054)
			(stroke
				(width 0.1)
				(type default)
			)
			(layer "B.Fab")
		)
		(pad "1" smd circle
			(at 0.40005 0 180)
			(size 0 0)
			(layers "B.Cu" "B.Mask" "B.Paste")
			(net "SMB_FAN_3V3AUX_BUF_SDA")
		)
		(pad "2" smd circle
			(at -0.40005 0 180)
			(size 0 0)
			(layers "B.Cu" "B.Mask" "B.Paste")
			(net "SMB_FAN_3V3AUX_BUF_R_SDA")
		)
	)
)
